# Barreleye-G2_Tri-mode BPX24-DVT-X01-SKU-BOM-X07-20171222_Final.xls.xlsx — TLA (bom)
| FOXCONN TECHNOLOGY GROUP |  |  |  |  |  |  |  |  |  |
| BILL OF MATERIAL |  |  |  |  |  |  |  |  |  |
| AA P/N | 1A42NC500-600-1 | CUSTOMER | <name> | Customer P/N | N/A | Product Code |  |  |  |
| AA P/N | 1A42NC500-600-2 |  |  |  |  |  |  |  |  |
| AA P/N | 1A42NC500-600-3 |  |  |  |  |  |  |  |  |
| PWA P/N |  | PWA DESCRIPTION | Tri-mode BackPlanex24 |  |  | PWA REV | DVT-X01 | Prepared By SE |  |
| Item | FOXCONN P/N | Customer P/N | Part Description | Manufacturer  Full Name | Manufacturer  Part Number | Qty | RoHS Status | Location | Remark |
| 1 | 7J-004-938 |  | L6 LABEL ( 12.7*11.1mm) | FOXCONN / EPD1 | 7J-004-938 | 1 | G |  |  |
| 2 | 1B51KUN00-600-G |  | 8_MYLAR-HDD-BP-FRONT_BG2 | FOXCONN / EPD5 | 1B51KUN00-600-G | 1 | G |  | Rev.X01 |
